(kicad_pcb
	(version 20260206)
	(generator "pcbnew")
	(generator_version "10.0")
	(general
		(thickness 1.6)
		(legacy_teardrops no)
	)
	(paper "A4")
	(title_block
		(title "panther-plus-userver — 13130-1b_20150205.brd")
		(comment 1 "Honey Badger (Wiwynn) / footprints 573-580 of 1509")
	)
	(layers
		(0 "F.Cu" signal "TOP")
		(4 "In1.Cu" signal "L2")
		(6 "In2.Cu" signal "L3")
		(8 "In3.Cu" signal "L4")
		(10 "In4.Cu" signal "L5")
		(12 "In5.Cu" signal "L6")
		(14 "In6.Cu" signal "L7")
		(16 "In7.Cu" signal "L8")
		(18 "In8.Cu" signal "L9")
		(20 "In9.Cu" signal "L10")
		(22 "In10.Cu" signal "L11")
		(2 "B.Cu" signal "BOTTOM")
		(9 "F.Adhes" user "F.Adhesive")
		(11 "B.Adhes" user "B.Adhesive")
		(13 "F.Paste" user "Package Geometry/Pastemask Top")
		(15 "B.Paste" user "Package Geometry/Pastemask Bottom")
		(5 "F.SilkS" user "Ref Des/Silkscreen Top")
		(7 "B.SilkS" user "Ref Des/Silkscreen Bottom")
		(1 "F.Mask" user "Board Geometry/Soldermask Top")
		(3 "B.Mask" user "Board Geometry/Soldermask Bottom")
		(17 "Dwgs.User" user "User.Drawings")
		(19 "Cmts.User" user "User.Comments")
		(21 "Eco1.User" user "User.Eco1")
		(23 "Eco2.User" user "User.Eco2")
		(25 "Edge.Cuts" user "Board Geometry/Outline")
		(27 "Margin" user)
		(31 "F.CrtYd" user "Package Geometry/Place Bound Top")
		(29 "B.CrtYd" user "Package Geometry/Place Bound Bottom")
		(35 "F.Fab" user "Ref Des/Assembly Top")
		(33 "B.Fab" user "Ref Des/Assembly Bottom")
	)
	(footprint ""
		(layer "F.Cu")
		(at 32.2072 -36.2204 180)
		(property "Reference" "R268"
			(at 0 0 180)
			(layer "F.SilkS")
			(hide yes)
			(effects
				(font
					(size 1.27 1.27)
				)
			)
		)
		(property "Value" "0R2J-2-GP"
			(at 0.064008 -3.993896 180)
			(unlocked yes)
			(layer "F.Fab")
			(hide yes)
			(effects
				(font
					(size 1.016 1.016)
					(thickness 0.1524)
				)
			)
		)
		(property "Device Type" "R402H16"
			(at 0.064008 -5.517896 180)
			(unlocked yes)
			(layer "F.Fab")
			(hide yes)
			(effects
				(font
					(size 1.016 1.016)
					(thickness 0.1524)
				)
			)
		)
		(duplicate_pad_numbers_are_jumpers no)
		(fp_rect
			(start -0.381 0.8382)
			(end 0.381 -0.8382)
			(stroke
				(width 0)
				(type default)
			)
			(fill no)
			(layer "F.CrtYd")
		)
		(fp_rect
			(start -0.381 0.8382)
			(end 0.381 -0.8382)
			(stroke
				(width 0)
				(type default)
			)
			(fill no)
			(layer "F.Fab")
		)
		(pad "1" smd custom
			(at 0 -0.4318 180)
			(size 0.127 0.127)
			(layers "F.Cu" "F.Mask" "F.Paste")
			(net "TDI_56")
			(options
				(clearance outline)
				(anchor circle)
			)
			(primitives
				(gr_poly
					(pts
						(arc
							(start -0.2032 -0.2794)
							(mid -0.239121 -0.264521)
							(end -0.254 -0.2286)
						)
						(arc
							(start -0.254 0.2286)
							(mid -0.239121 0.264521)
							(end -0.2032 0.2794)
						)
						(arc
							(start 0.2032 0.2794)
							(mid 0.239121 0.264521)
							(end 0.254 0.2286)
						)
						(arc
							(start 0.254 -0.2286)
							(mid 0.239121 -0.264521)
							(end 0.2032 -0.2794)
						)
					)
					(width 0)
					(fill yes)
				)
			)
		)
		(pad "2" smd custom
			(at 0 0.4318 180)
			(size 0.127 0.127)
			(layers "F.Cu" "F.Mask" "F.Paste")
			(net "XDP_SOC_CPU_TDI")
			(options
				(clearance outline)
				(anchor circle)
			)
			(primitives
				(gr_poly
					(pts
						(arc
							(start -0.2032 -0.2794)
							(mid -0.239121 -0.264521)
							(end -0.254 -0.2286)
						)
						(arc
							(start -0.254 0.2286)
							(mid -0.239121 0.264521)
							(end -0.2032 0.2794)
						)
						(arc
							(start 0.2032 0.2794)
							(mid 0.239121 0.264521)
							(end 0.254 0.2286)
						)
						(arc
							(start 0.254 -0.2286)
							(mid 0.239121 -0.264521)
							(end 0.2032 -0.2794)
						)
					)
					(width 0)
					(fill yes)
				)
			)
		)
	)
	(footprint ""
		(layer "F.Cu")
		(at 154.94 -11.684 -90)
		(property "Reference" "R385"
			(at 0 0 270)
			(layer "F.SilkS")
			(hide yes)
			(effects
				(font
					(size 1.27 1.27)
				)
			)
		)
		(property "Value" "100R2F-L1-GP-U"
			(at 0.064008 -3.993896 270)
			(unlocked yes)
			(layer "F.Fab")
			(hide yes)
			(effects
				(font
					(size 1.016 1.016)
					(thickness 0.1524)
				)
			)
		)
		(property "Device Type" "R402H14"
			(at 0.064008 -5.517896 270)
			(unlocked yes)
			(layer "F.Fab")
			(hide yes)
			(effects
				(font
					(size 1.016 1.016)
					(thickness 0.1524)
				)
			)
		)
		(duplicate_pad_numbers_are_jumpers no)
		(fp_rect
			(start -0.381 0.8382)
			(end 0.381 -0.8382)
			(stroke
				(width 0)
				(type default)
			)
			(fill no)
			(layer "F.CrtYd")
		)
		(fp_rect
			(start -0.381 0.8382)
			(end 0.381 -0.8382)
			(stroke
				(width 0)
				(type default)
			)
			(fill no)
			(layer "F.Fab")
		)
		(pad "1" smd custom
			(at 0 -0.4318 270)
			(size 0.127 0.127)
			(layers "F.Cu" "F.Mask" "F.Paste")
			(net "PV_VDDR")
			(options
				(clearance outline)
				(anchor circle)
			)
			(primitives
				(gr_poly
					(pts
						(arc
							(start -0.2032 -0.2794)
							(mid -0.239121 -0.264521)
							(end -0.254 -0.2286)
						)
						(arc
							(start -0.254 0.2286)
							(mid -0.239121 0.264521)
							(end -0.2032 0.2794)
						)
						(arc
							(start 0.2032 0.2794)
							(mid 0.239121 0.264521)
							(end 0.254 0.2286)
						)
						(arc
							(start 0.254 -0.2286)
							(mid 0.239121 -0.264521)
							(end 0.2032 -0.2794)
						)
					)
					(width 0)
					(fill yes)
				)
			)
		)
		(pad "2" smd custom
			(at 0 0.4318 270)
			(size 0.127 0.127)
			(layers "F.Cu" "F.Mask" "F.Paste")
			(net "DDR3_M_B_VREF_CA")
			(options
				(clearance outline)
				(anchor circle)
			)
			(primitives
				(gr_poly
					(pts
						(arc
							(start -0.2032 -0.2794)
							(mid -0.239121 -0.264521)
							(end -0.254 -0.2286)
						)
						(arc
							(start -0.254 0.2286)
							(mid -0.239121 0.264521)
							(end -0.2032 0.2794)
						)
						(arc
							(start 0.2032 0.2794)
							(mid 0.239121 0.264521)
							(end 0.254 0.2286)
						)
						(arc
							(start 0.254 -0.2286)
							(mid 0.239121 -0.264521)
							(end 0.2032 -0.2794)
						)
					)
					(width 0)
					(fill yes)
				)
			)
		)
	)
	(footprint ""
		(layer "F.Cu")
		(at 50.419 -65.024)
		(property "Reference" "PR33"
			(at 0 0 0)
			(layer "F.SilkS")
			(hide yes)
			(effects
				(font
					(size 1.27 1.27)
				)
			)
		)
		(property "Value" "120R3F-L-GP"
			(at -0.0254 -2.0193 0)
			(unlocked yes)
			(layer "F.Fab")
			(hide yes)
			(effects
				(font
					(size 1.016 1.016)
					(thickness 0.1524)
				)
			)
		)
		(property "Device Type" "R603H22"
			(at -0.0254 -3.5433 0)
			(unlocked yes)
			(layer "F.Fab")
			(hide yes)
			(effects
				(font
					(size 1.016 1.016)
					(thickness 0.1524)
				)
			)
		)
		(duplicate_pad_numbers_are_jumpers no)
		(fp_line
			(start -0.2032 0)
			(end -0.4191 0)
			(stroke
				(width 0.2032)
				(type default)
			)
			(layer "F.SilkS")
		)
		(fp_line
			(start 0.4318 0)
			(end 0.2032 0)
			(stroke
				(width 0.2032)
				(type default)
			)
			(layer "F.SilkS")
		)
		(fp_rect
			(start -0.635 1.1811)
			(end 0.635 -1.1811)
			(stroke
				(width 0)
				(type default)
			)
			(fill no)
			(layer "F.CrtYd")
		)
		(fp_rect
			(start -0.635 1.1811)
			(end 0.635 -1.1811)
			(stroke
				(width 0)
				(type default)
			)
			(fill no)
			(layer "F.Fab")
		)
		(pad "1" smd custom
			(at 0 -0.6604)
			(size 0.19685 0.19685)
			(layers "F.Cu" "F.Mask" "F.Paste")
			(net "PVNN")
			(options
				(clearance outline)
				(anchor circle)
			)
			(primitives
				(gr_poly
					(pts
						(arc
							(start 0.508 -0.2921)
							(mid 0.478242 -0.363942)
							(end 0.4064 -0.3937)
						)
						(arc
							(start -0.4064 -0.3937)
							(mid -0.478242 -0.363942)
							(end -0.508 -0.2921)
						)
						(arc
							(start -0.508 0.2921)
							(mid -0.478242 0.363942)
							(end -0.4064 0.3937)
						)
						(arc
							(start 0.4064 0.3937)
							(mid 0.478242 0.363942)
							(end 0.508 0.2921)
						)
					)
					(width 0)
					(fill yes)
				)
			)
		)
		(pad "2" smd custom
			(at 0 0.6604)
			(size 0.19685 0.19685)
			(layers "F.Cu" "F.Mask" "F.Paste")
			(net "GND")
			(options
				(clearance outline)
				(anchor circle)
			)
			(primitives
				(gr_poly
					(pts
						(arc
							(start 0.508 -0.2921)
							(mid 0.478242 -0.363942)
							(end 0.4064 -0.3937)
						)
						(arc
							(start -0.4064 -0.3937)
							(mid -0.478242 -0.363942)
							(end -0.508 -0.2921)
						)
						(arc
							(start -0.508 0.2921)
							(mid -0.478242 0.363942)
							(end -0.4064 0.3937)
						)
						(arc
							(start 0.4064 0.3937)
							(mid 0.478242 0.363942)
							(end 0.508 0.2921)
						)
					)
					(width 0)
					(fill yes)
				)
			)
		)
	)
	(footprint ""
		(layer "F.Cu")
		(at 6.6294 -28.7274 180)
		(property "Reference" "PC94"
			(at 0 0 180)
			(layer "F.SilkS")
			(hide yes)
			(effects
				(font
					(size 1.27 1.27)
				)
			)
		)
		(property "Value" "SC22U25V5MX-GP"
			(at 0 -4.9022 180)
			(unlocked yes)
			(layer "F.Fab")
			(hide yes)
			(effects
				(font
					(size 1.016 1.016)
					(thickness 0.1524)
				)
			)
		)
		(property "Device Type" "C805H58"
			(at 0 -6.8072 180)
			(unlocked yes)
			(layer "F.Fab")
			(hide yes)
			(effects
				(font
					(size 1.016 1.016)
					(thickness 0.1524)
				)
			)
		)
		(duplicate_pad_numbers_are_jumpers no)
		(fp_line
			(start 0.6096 0)
			(end -0.6096 0)
			(stroke
				(width 0.3048)
				(type default)
			)
			(layer "F.SilkS")
		)
		(fp_poly
			(pts
				(xy -0.9017 1.4351) (xy 0.9017 1.4351) (xy 0.9017 -1.4351) (xy -0.9017 -1.4351)
			)
			(stroke
				(width 0)
				(type default)
			)
			(fill no)
			(layer "F.CrtYd")
		)
		(fp_poly
			(pts
				(xy 0.9017 1.4351) (xy 0.9017 -1.4351) (xy -0.9017 -1.4351) (xy -0.9017 1.4351)
			)
			(stroke
				(width 0)
				(type default)
			)
			(fill no)
			(layer "F.Fab")
		)
		(pad "1" smd rect
			(at 0 -0.8382 180)
			(size 1.5494 0.9398)
			(layers "F.Cu" "F.Mask" "F.Paste")
			(net "P1V0_VIN")
		)
		(pad "2" smd rect
			(at 0 0.8382 180)
			(size 1.5494 0.9398)
			(layers "F.Cu" "F.Mask" "F.Paste")
			(net "GND")
		)
	)
	(footprint ""
		(layer "F.Cu")
		(at 37.338 -49.784 90)
		(property "Reference" "L3"
			(at 0 0 90)
			(layer "F.SilkS")
			(hide yes)
			(effects
				(font
					(size 1.27 1.27)
				)
			)
		)
		(property "Value" "BLM18PG330SN1D-GP"
			(at -0.0254 -2.0193 90)
			(unlocked yes)
			(layer "F.Fab")
			(hide yes)
			(effects
				(font
					(size 1.016 1.016)
					(thickness 0.1524)
				)
			)
		)
		(property "Device Type" "L1608-UH38"
			(at -0.0254 -3.5433 90)
			(unlocked yes)
			(layer "F.Fab")
			(hide yes)
			(effects
				(font
					(size 1.016 1.016)
					(thickness 0.1524)
				)
			)
		)
		(duplicate_pad_numbers_are_jumpers no)
		(fp_line
			(start -0.4064 0)
			(end 0.4064 0)
			(stroke
				(width 0.2032)
				(type default)
			)
			(layer "F.SilkS")
		)
		(fp_rect
			(start -0.635 1.1811)
			(end 0.635 -1.1811)
			(stroke
				(width 0)
				(type default)
			)
			(fill no)
			(layer "F.CrtYd")
		)
		(fp_rect
			(start -0.635 1.1811)
			(end 0.635 -1.1811)
			(stroke
				(width 0)
				(type default)
			)
			(fill no)
			(layer "F.Fab")
		)
		(pad "1" smd custom
			(at 0 -0.6604 90)
			(size 0.19685 0.19685)
			(layers "F.Cu" "F.Mask" "F.Paste")
			(net "P3V3_STBY")
			(options
				(clearance outline)
				(anchor circle)
			)
			(primitives
				(gr_poly
					(pts
						(arc
							(start 0.508 -0.2921)
							(mid 0.478242 -0.363942)
							(end 0.4064 -0.3937)
						)
						(arc
							(start -0.4064 -0.3937)
							(mid -0.478242 -0.363942)
							(end -0.508 -0.2921)
						)
						(arc
							(start -0.508 0.2921)
							(mid -0.478242 0.363942)
							(end -0.4064 0.3937)
						)
						(arc
							(start 0.4064 0.3937)
							(mid 0.478242 0.363942)
							(end 0.508 0.2921)
						)
					)
					(width 0)
					(fill yes)
				)
			)
		)
		(pad "2" smd custom
			(at 0 0.6604 90)
			(size 0.19685 0.19685)
			(layers "F.Cu" "F.Mask" "F.Paste")
			(net "P3V3_CLK_R_PCI")
			(options
				(clearance outline)
				(anchor circle)
			)
			(primitives
				(gr_poly
					(pts
						(arc
							(start 0.508 -0.2921)
							(mid 0.478242 -0.363942)
							(end 0.4064 -0.3937)
						)
						(arc
							(start -0.4064 -0.3937)
							(mid -0.478242 -0.363942)
							(end -0.508 -0.2921)
						)
						(arc
							(start -0.508 0.2921)
							(mid -0.478242 0.363942)
							(end -0.4064 0.3937)
						)
						(arc
							(start 0.4064 0.3937)
							(mid 0.478242 0.363942)
							(end 0.508 0.2921)
						)
					)
					(width 0)
					(fill yes)
				)
			)
		)
	)
	(footprint ""
		(layer "F.Cu")
		(at 36.83 -39.116)
		(property "Reference" "R243"
			(at 0 0 0)
			(layer "F.SilkS")
			(hide yes)
			(effects
				(font
					(size 1.27 1.27)
				)
			)
		)
		(property "Value" "2K2R2F-GP"
			(at 0.064008 -3.993896 0)
			(unlocked yes)
			(layer "F.Fab")
			(hide yes)
			(effects
				(font
					(size 1.016 1.016)
					(thickness 0.1524)
				)
			)
		)
		(property "Device Type" "R402H16"
			(at 0.064008 -5.517896 0)
			(unlocked yes)
			(layer "F.Fab")
			(hide yes)
			(effects
				(font
					(size 1.016 1.016)
					(thickness 0.1524)
				)
			)
		)
		(duplicate_pad_numbers_are_jumpers no)
		(fp_rect
			(start -0.381 0.8382)
			(end 0.381 -0.8382)
			(stroke
				(width 0)
				(type default)
			)
			(fill no)
			(layer "F.CrtYd")
		)
		(fp_rect
			(start -0.381 0.8382)
			(end 0.381 -0.8382)
			(stroke
				(width 0)
				(type default)
			)
			(fill no)
			(layer "F.Fab")
		)
		(pad "1" smd custom
			(at 0 -0.4318)
			(size 0.127 0.127)
			(layers "F.Cu" "F.Mask" "F.Paste")
			(net "P3V3_RTC")
			(options
				(clearance outline)
				(anchor circle)
			)
			(primitives
				(gr_poly
					(pts
						(arc
							(start -0.2032 -0.2794)
							(mid -0.239121 -0.264521)
							(end -0.254 -0.2286)
						)
						(arc
							(start -0.254 0.2286)
							(mid -0.239121 0.264521)
							(end -0.2032 0.2794)
						)
						(arc
							(start 0.2032 0.2794)
							(mid 0.239121 0.264521)
							(end 0.254 0.2286)
						)
						(arc
							(start 0.254 -0.2286)
							(mid 0.239121 -0.264521)
							(end 0.2032 -0.2794)
						)
					)
					(width 0)
					(fill yes)
				)
			)
		)
		(pad "2" smd custom
			(at 0 0.4318)
			(size 0.127 0.127)
			(layers "F.Cu" "F.Mask" "F.Paste")
			(net "XDP_RTEST#")
			(options
				(clearance outline)
				(anchor circle)
			)
			(primitives
				(gr_poly
					(pts
						(arc
							(start -0.2032 -0.2794)
							(mid -0.239121 -0.264521)
							(end -0.254 -0.2286)
						)
						(arc
							(start -0.254 0.2286)
							(mid -0.239121 0.264521)
							(end -0.2032 0.2794)
						)
						(arc
							(start 0.2032 0.2794)
							(mid 0.239121 0.264521)
							(end 0.254 0.2286)
						)
						(arc
							(start 0.254 -0.2286)
							(mid 0.239121 -0.264521)
							(end 0.2032 -0.2794)
						)
					)
					(width 0)
					(fill yes)
				)
			)
		)
	)
	(footprint ""
		(layer "F.Cu")
		(at 52.2224 -12.827 180)
		(property "Reference" "C315"
			(at 0 0 180)
			(layer "F.SilkS")
			(hide yes)
			(effects
				(font
					(size 1.27 1.27)
				)
			)
		)
		(property "Value" "SCD047U25V2KX-GP"
			(at 1.8923 -1.2065 180)
			(unlocked yes)
			(layer "F.Fab")
			(hide yes)
			(effects
				(font
					(size 1.016 1.016)
					(thickness 0.1524)
				)
			)
		)
		(property "Device Type" "C402H22"
			(at 1.8923 -2.7305 180)
			(unlocked yes)
			(layer "F.Fab")
			(hide yes)
			(effects
				(font
					(size 1.016 1.016)
					(thickness 0.1524)
				)
			)
		)
		(duplicate_pad_numbers_are_jumpers no)
		(fp_rect
			(start -0.381 0.7366)
			(end 0.381 -0.7366)
			(stroke
				(width 0)
				(type default)
			)
			(fill no)
			(layer "F.CrtYd")
		)
		(fp_rect
			(start -0.381 0.7366)
			(end 0.381 -0.7366)
			(stroke
				(width 0)
				(type default)
			)
			(fill no)
			(layer "F.Fab")
		)
		(pad "1" smd custom
			(at 0 -0.4572 180)
			(size 0.1143 0.1143)
			(layers "F.Cu" "F.Mask" "F.Paste")
			(net "CPU_GBE_RX_C_DN0")
			(options
				(clearance outline)
				(anchor circle)
			)
			(primitives
				(gr_poly
					(pts
						(arc
							(start -0.254 -0.1778)
							(mid -0.239121 -0.213721)
							(end -0.2032 -0.2286)
						)
						(arc
							(start 0.2032 -0.2286)
							(mid 0.239121 -0.213721)
							(end 0.254 -0.1778)
						)
						(arc
							(start 0.254 0.1778)
							(mid 0.239121 0.213721)
							(end 0.2032 0.2286)
						)
						(arc
							(start -0.2032 0.2286)
							(mid -0.239121 0.213721)
							(end -0.254 0.1778)
						)
					)
					(width 0)
					(fill yes)
				)
			)
		)
		(pad "2" smd custom
			(at 0 0.4572 180)
			(size 0.1143 0.1143)
			(layers "F.Cu" "F.Mask" "F.Paste")
			(net "CPU_GBE_RX_DN0")
			(options
				(clearance outline)
				(anchor circle)
			)
			(primitives
				(gr_poly
					(pts
						(arc
							(start -0.254 -0.1778)
							(mid -0.239121 -0.213721)
							(end -0.2032 -0.2286)
						)
						(arc
							(start 0.2032 -0.2286)
							(mid 0.239121 -0.213721)
							(end 0.254 -0.1778)
						)
						(arc
							(start 0.254 0.1778)
							(mid 0.239121 0.213721)
							(end 0.2032 0.2286)
						)
						(arc
							(start -0.2032 0.2286)
							(mid -0.239121 0.213721)
							(end -0.254 0.1778)
						)
					)
					(width 0)
					(fill yes)
				)
			)
		)
	)
	(footprint ""
		(layer "F.Cu")
		(at 16.2052 -52.578)
		(property "Reference" "PR76"
			(at 0 0 0)
			(layer "F.SilkS")
			(hide yes)
			(effects
				(font
					(size 1.27 1.27)
				)
			)
		)
		(property "Value" "5K6R2F-2-GP"
			(at 1.7907 -1.1176 0)
			(unlocked yes)
			(layer "F.Fab")
			(hide yes)
			(effects
				(font
					(size 1.016 1.016)
					(thickness 0.1524)
				)
			)
		)
		(property "Device Type" "R402H16"
			(at 1.7907 -2.6416 0)
			(unlocked yes)
			(layer "F.Fab")
			(hide yes)
			(effects
				(font
					(size 1.016 1.016)
					(thickness 0.1524)
				)
			)
		)
		(duplicate_pad_numbers_are_jumpers no)
		(fp_rect
			(start -0.381 0.8382)
			(end 0.381 -0.8382)
			(stroke
				(width 0)
				(type default)
			)
			(fill no)
			(layer "F.CrtYd")
		)
		(fp_rect
			(start -0.381 0.8382)
			(end 0.381 -0.8382)
			(stroke
				(width 0)
				(type default)
			)
			(fill no)
			(layer "F.Fab")
		)
		(pad "1" smd custom
			(at 0 -0.4318)
			(size 0.127 0.127)
			(layers "F.Cu" "F.Mask" "F.Paste")
			(net "VR_PVCCP_VW")
			(options
				(clearance outline)
				(anchor circle)
			)
			(primitives
				(gr_poly
					(pts
						(arc
							(start -0.2032 -0.2794)
							(mid -0.239121 -0.264521)
							(end -0.254 -0.2286)
						)
						(arc
							(start -0.254 0.2286)
							(mid -0.239121 0.264521)
							(end -0.2032 0.2794)
						)
						(arc
							(start 0.2032 0.2794)
							(mid 0.239121 0.264521)
							(end 0.254 0.2286)
						)
						(arc
							(start 0.254 -0.2286)
							(mid 0.239121 -0.264521)
							(end 0.2032 -0.2794)
						)
					)
					(width 0)
					(fill yes)
				)
			)
		)
		(pad "2" smd custom
			(at 0 0.4318)
			(size 0.127 0.127)
			(layers "F.Cu" "F.Mask" "F.Paste")
			(net "VR_PVCCP_COMP")
			(options
				(clearance outline)
				(anchor circle)
			)
			(primitives
				(gr_poly
					(pts
						(arc
							(start -0.2032 -0.2794)
							(mid -0.239121 -0.264521)
							(end -0.254 -0.2286)
						)
						(arc
							(start -0.254 0.2286)
							(mid -0.239121 0.264521)
							(end -0.2032 0.2794)
						)
						(arc
							(start 0.2032 0.2794)
							(mid 0.239121 0.264521)
							(end 0.254 0.2286)
						)
						(arc
							(start 0.254 -0.2286)
							(mid 0.239121 -0.264521)
							(end 0.2032 -0.2794)
						)
					)
					(width 0)
					(fill yes)
				)
			)
		)
	)
)
